(kicad_pcb
	(version 20260206)
	(generator "pcbnew")
	(generator_version "10.0")
	(general
		(thickness 1.6)
		(legacy_teardrops no)
	)
	(paper "A4")
	(title_block
		(title "v1-chassis-manager — T6M_CM_d_v01_1031_1645.brd")
		(comment 1 "Open CloudServer (Microsoft) / footprints 522-531 of 2512")
	)
	(layers
		(0 "F.Cu" signal "TOP")
		(4 "In1.Cu" signal "GND1")
		(6 "In2.Cu" signal "IN1")
		(8 "In3.Cu" signal "VCC1")
		(10 "In4.Cu" signal "VCC2")
		(12 "In5.Cu" signal "GND2")
		(14 "In6.Cu" signal "IN2")
		(16 "In7.Cu" signal "IN3")
		(18 "In8.Cu" signal "GND3")
		(2 "B.Cu" signal "BOTTOM")
		(9 "F.Adhes" user "F.Adhesive")
		(11 "B.Adhes" user "B.Adhesive")
		(13 "F.Paste" user "Package Geometry/Pastemask Top")
		(15 "B.Paste" user "Package Geometry/Pastemask Bottom")
		(5 "F.SilkS" user "Ref Des/Silkscreen Top")
		(7 "B.SilkS" user "Ref Des/Silkscreen Bottom")
		(1 "F.Mask" user "Board Geometry/Soldermask Top")
		(3 "B.Mask" user "Board Geometry/Soldermask Bottom")
		(17 "Dwgs.User" user "User.Drawings")
		(19 "Cmts.User" user "User.Comments")
		(21 "Eco1.User" user "User.Eco1")
		(23 "Eco2.User" user "User.Eco2")
		(25 "Edge.Cuts" user "Board Geometry/Outline")
		(27 "Margin" user)
		(31 "F.CrtYd" user "Package Geometry/Place Bound Top")
		(29 "B.CrtYd" user "Package Geometry/Place Bound Bottom")
		(35 "F.Fab" user "Ref Des/Assembly Top")
		(33 "B.Fab" user "Ref Des/Assembly Bottom")
	)
	(footprint ""
		(layer "F.Cu")
		(at 144.916652 -140.21435)
		(property "Reference" "R286"
			(at -0.990346 17.852644 0)
			(unlocked yes)
			(layer "F.SilkS")
			(effects
				(font
					(size 0.7874 0.5842)
					(thickness 0.1524)
				)
				(justify left)
			)
		)
		(property "Value" ""
			(at 0 0 0)
			(layer "F.Fab")
			(effects
				(font
					(size 1.27 1.27)
				)
			)
		)
		(duplicate_pad_numbers_are_jumpers no)
		(fp_line
			(start -0.7874 -0.4064)
			(end 0.7874 -0.4064)
			(stroke
				(width 0.1524)
				(type default)
			)
			(layer "F.SilkS")
		)
		(fp_line
			(start -0.7874 0.4064)
			(end -0.7874 -0.4064)
			(stroke
				(width 0.1524)
				(type default)
			)
			(layer "F.SilkS")
		)
		(fp_line
			(start 0.7874 -0.4064)
			(end 0.7874 0.4064)
			(stroke
				(width 0.1524)
				(type default)
			)
			(layer "F.SilkS")
		)
		(fp_line
			(start 0.7874 0.4064)
			(end -0.7874 0.4064)
			(stroke
				(width 0.1524)
				(type default)
			)
			(layer "F.SilkS")
		)
		(fp_poly
			(pts
				(xy -0.508 0.2794) (xy -0.508 0.2286) (xy -0.635 0.2286) (xy -0.635 -0.254) (xy -0.5334 -0.254)
				(xy -0.5334 -0.2794) (xy 0.5334 -0.2794) (xy 0.5334 -0.254) (xy 0.635 -0.254) (xy 0.635 0.254) (xy 0.5334 0.254)
				(xy 0.5334 0.2794)
			)
			(stroke
				(width 0)
				(type default)
			)
			(fill no)
			(layer "F.CrtYd")
		)
		(pad "1" smd rect
			(at 0.40005 0)
			(size 0.4572 0.508)
			(layers "F.Cu" "F.Mask" "F.Paste")
			(net "GND")
		)
		(pad "2" smd rect
			(at -0.40005 0)
			(size 0.4572 0.508)
			(layers "F.Cu" "F.Mask" "F.Paste")
			(net "PCIE_SW_TEST3")
		)
	)
	(footprint ""
		(layer "F.Cu")
		(at 60.129166 -96.709992 -90)
		(property "Reference" "R56"
			(at 54.98719 -28.490164 90)
			(unlocked yes)
			(layer "F.SilkS")
			(effects
				(font
					(size 0.7874 0.5842)
					(thickness 0.1524)
				)
				(justify left)
			)
		)
		(property "Value" ""
			(at 0 0 270)
			(layer "F.Fab")
			(effects
				(font
					(size 1.27 1.27)
				)
			)
		)
		(duplicate_pad_numbers_are_jumpers no)
		(fp_line
			(start -0.7874 0.4064)
			(end -0.7874 -0.4064)
			(stroke
				(width 0.1524)
				(type default)
			)
			(layer "F.SilkS")
		)
		(fp_line
			(start 0.7874 0.4064)
			(end -0.7874 0.4064)
			(stroke
				(width 0.1524)
				(type default)
			)
			(layer "F.SilkS")
		)
		(fp_line
			(start -0.7874 -0.4064)
			(end 0.7874 -0.4064)
			(stroke
				(width 0.1524)
				(type default)
			)
			(layer "F.SilkS")
		)
		(fp_line
			(start 0.7874 -0.4064)
			(end 0.7874 0.4064)
			(stroke
				(width 0.1524)
				(type default)
			)
			(layer "F.SilkS")
		)
		(fp_poly
			(pts
				(xy -0.508 0.2794) (xy -0.508 0.2286) (xy -0.635 0.2286) (xy -0.635 -0.254) (xy -0.5334 -0.254)
				(xy -0.5334 -0.2794) (xy 0.5334 -0.2794) (xy 0.5334 -0.254) (xy 0.635 -0.254) (xy 0.635 0.254) (xy 0.5334 0.254)
				(xy 0.5334 0.2794)
			)
			(stroke
				(width 0)
				(type default)
			)
			(fill no)
			(layer "F.CrtYd")
		)
		(pad "1" smd rect
			(at 0.40005 0 270)
			(size 0.4572 0.508)
			(layers "F.Cu" "F.Mask" "F.Paste")
			(net "PD_CPU_NODE1_DFX_GPIO_GRP1_0")
		)
		(pad "2" smd rect
			(at -0.40005 0 270)
			(size 0.4572 0.508)
			(layers "F.Cu" "F.Mask" "F.Paste")
			(net "GND")
		)
	)
	(footprint ""
		(layer "F.Cu")
		(at 76.901548 -101.200966)
		(property "Reference" "R1051"
			(at -1.890268 -2.053082 0)
			(unlocked yes)
			(layer "F.SilkS")
			(effects
				(font
					(size 0.7874 0.5842)
					(thickness 0.1524)
				)
				(justify left)
			)
		)
		(property "Value" ""
			(at 0 0 0)
			(layer "F.Fab")
			(effects
				(font
					(size 1.27 1.27)
				)
			)
		)
		(duplicate_pad_numbers_are_jumpers no)
		(fp_line
			(start -0.7874 -0.4064)
			(end 0.7874 -0.4064)
			(stroke
				(width 0.1524)
				(type default)
			)
			(layer "F.SilkS")
		)
		(fp_line
			(start -0.7874 0.4064)
			(end -0.7874 -0.4064)
			(stroke
				(width 0.1524)
				(type default)
			)
			(layer "F.SilkS")
		)
		(fp_line
			(start 0.7874 -0.4064)
			(end 0.7874 0.4064)
			(stroke
				(width 0.1524)
				(type default)
			)
			(layer "F.SilkS")
		)
		(fp_line
			(start 0.7874 0.4064)
			(end -0.7874 0.4064)
			(stroke
				(width 0.1524)
				(type default)
			)
			(layer "F.SilkS")
		)
		(fp_poly
			(pts
				(xy -0.508 0.2794) (xy -0.508 0.2286) (xy -0.635 0.2286) (xy -0.635 -0.254) (xy -0.5334 -0.254)
				(xy -0.5334 -0.2794) (xy 0.5334 -0.2794) (xy 0.5334 -0.254) (xy 0.635 -0.254) (xy 0.635 0.254) (xy 0.5334 0.254)
				(xy 0.5334 0.2794)
			)
			(stroke
				(width 0)
				(type default)
			)
			(fill no)
			(layer "F.CrtYd")
		)
		(pad "1" smd rect
			(at 0.40005 0)
			(size 0.4572 0.508)
			(layers "F.Cu" "F.Mask" "F.Paste")
			(net "P3V3_STB_NODE1")
		)
		(pad "2" smd rect
			(at -0.40005 0)
			(size 0.4572 0.508)
			(layers "F.Cu" "F.Mask" "F.Paste")
			(net "FM_OSC_NODE1_OSC_NC")
		)
	)
	(footprint ""
		(layer "F.Cu")
		(at 143.748252 -25.812242 90)
		(property "Reference" "L36"
			(at 1.223772 0.17907 90)
			(unlocked yes)
			(layer "F.SilkS")
			(effects
				(font
					(size 0.7874 0.5842)
					(thickness 0.1524)
				)
				(justify left)
			)
		)
		(property "Value" ""
			(at 0 0 90)
			(layer "F.Fab")
			(effects
				(font
					(size 1.27 1.27)
				)
			)
		)
		(duplicate_pad_numbers_are_jumpers no)
		(fp_line
			(start 0.7874 -0.4064)
			(end 0.7874 0.4064)
			(stroke
				(width 0.1524)
				(type default)
			)
			(layer "F.SilkS")
		)
		(fp_line
			(start -0.7874 -0.4064)
			(end 0.7874 -0.4064)
			(stroke
				(width 0.1524)
				(type default)
			)
			(layer "F.SilkS")
		)
		(fp_line
			(start 0.7874 0.4064)
			(end -0.7874 0.4064)
			(stroke
				(width 0.1524)
				(type default)
			)
			(layer "F.SilkS")
		)
		(fp_line
			(start 0.0889 0.4064)
			(end 0.0889 -0.4064)
			(stroke
				(width 0.1524)
				(type default)
			)
			(layer "F.SilkS")
		)
		(fp_line
			(start -0.0889 0.4064)
			(end -0.0889 -0.4064)
			(stroke
				(width 0.1524)
				(type default)
			)
			(layer "F.SilkS")
		)
		(fp_line
			(start -0.7874 0.4064)
			(end -0.7874 -0.4064)
			(stroke
				(width 0.1524)
				(type default)
			)
			(layer "F.SilkS")
		)
		(fp_poly
			(pts
				(xy -0.5334 0.254) (xy -0.635 0.254) (xy -0.635 0.2286) (xy -0.635 -0.254) (xy -0.5334 -0.254) (xy -0.5334 -0.2794)
				(xy 0.5334 -0.2794) (xy 0.5334 -0.254) (xy 0.635 -0.254) (xy 0.635 0.254) (xy 0.5334 0.254) (xy 0.5334 0.2794)
				(xy -0.508 0.2794) (xy -0.5334 0.2794)
			)
			(stroke
				(width 0)
				(type default)
			)
			(fill no)
			(layer "F.CrtYd")
		)
		(pad "1" smd rect
			(at 0.40005 0 90)
			(size 0.4572 0.508)
			(layers "F.Cu" "F.Mask" "F.Paste")
			(net "SIO_AVCC")
		)
		(pad "2" smd rect
			(at -0.40005 0 90)
			(size 0.4572 0.508)
			(layers "F.Cu" "F.Mask" "F.Paste")
			(net "P5V_NODE1")
		)
	)
	(footprint ""
		(layer "F.Cu")
		(at 123.70816 -163.475416)
		(property "Reference" "C567"
			(at 29.783278 46.44517 0)
			(unlocked yes)
			(layer "F.SilkS")
			(effects
				(font
					(size 0.7874 0.5842)
					(thickness 0.1524)
				)
				(justify left)
			)
		)
		(property "Value" ""
			(at 0 0 0)
			(layer "F.Fab")
			(effects
				(font
					(size 1.27 1.27)
				)
			)
		)
		(duplicate_pad_numbers_are_jumpers no)
		(fp_line
			(start -0.7874 -0.4064)
			(end 0.7874 -0.4064)
			(stroke
				(width 0.1524)
				(type default)
			)
			(layer "F.SilkS")
		)
		(fp_line
			(start -0.7874 0.4064)
			(end -0.7874 -0.4064)
			(stroke
				(width 0.1524)
				(type default)
			)
			(layer "F.SilkS")
		)
		(fp_line
			(start 0 0.381)
			(end 0 -0.381)
			(stroke
				(width 0.1524)
				(type default)
			)
			(layer "F.SilkS")
		)
		(fp_line
			(start 0.7874 -0.4064)
			(end 0.7874 0.4064)
			(stroke
				(width 0.1524)
				(type default)
			)
			(layer "F.SilkS")
		)
		(fp_line
			(start 0.7874 0.4064)
			(end -0.7874 0.4064)
			(stroke
				(width 0.1524)
				(type default)
			)
			(layer "F.SilkS")
		)
		(fp_poly
			(pts
				(xy -0.5334 0.254) (xy -0.635 0.254) (xy -0.635 0.2286) (xy -0.635 -0.254) (xy -0.5334 -0.254) (xy -0.5334 -0.2794)
				(xy 0.5334 -0.2794) (xy 0.5334 -0.254) (xy 0.635 -0.254) (xy 0.635 0.254) (xy 0.5334 0.254) (xy 0.5334 0.2794)
				(xy -0.508 0.2794) (xy -0.5334 0.2794)
			)
			(stroke
				(width 0)
				(type default)
			)
			(fill no)
			(layer "F.CrtYd")
		)
		(pad "1" smd rect
			(at 0.40005 0)
			(size 0.4572 0.508)
			(layers "F.Cu" "F.Mask" "F.Paste")
			(net "GND")
		)
		(pad "2" smd rect
			(at -0.40005 0)
			(size 0.4572 0.508)
			(layers "F.Cu" "F.Mask" "F.Paste")
			(net "P3V3_NODE1")
		)
	)
	(footprint ""
		(layer "F.Cu")
		(at 102.596188 -158.497524)
		(property "Reference" "PJ4"
			(at 2.828798 0.984504 90)
			(unlocked yes)
			(layer "F.SilkS")
			(effects
				(font
					(size 0.635 0.4064)
					(thickness 0.1524)
				)
				(justify left)
			)
		)
		(property "Value" ""
			(at 0 0 0)
			(layer "F.Fab")
			(effects
				(font
					(size 1.27 1.27)
				)
			)
		)
		(duplicate_pad_numbers_are_jumpers no)
		(fp_poly
			(pts
				(xy 0.2794 0.907796) (xy 0.254 0.907796) (xy 0.254 1.0414) (xy -0.254 1.0414) (xy -0.254 1.034796)
				(xy -0.254 0.933196) (xy -0.2794 0.933196) (xy -0.2794 -0.133604) (xy -0.254 -0.133604) (xy -0.254 -0.235204)
				(xy 0.254 -0.235204) (xy 0.254 -0.133604) (xy 0.2794 -0.133604)
			)
			(stroke
				(width 0)
				(type default)
			)
			(fill no)
			(layer "F.CrtYd")
		)
		(pad "1" smd custom
			(at 0 -0.000254)
			(size 0.127 0.127)
			(layers "F.Cu" "F.Mask" "F.Paste")
			(net "FM_CPLD_NODE1_P1V8_STB_EN")
			(options
				(clearance outline)
				(anchor circle)
			)
			(primitives
				(gr_poly
					(pts
						(xy -0.127 0.508) (xy -0.127 -0.0508) (xy -0.254 -0.0508) (xy -0.254 -0.508) (xy 0.254 -0.508)
						(xy 0.254 -0.0508) (xy 0.127 -0.0508) (xy 0.127 0.508)
					)
					(width 0)
					(fill yes)
				)
			)
		)
		(pad "2" smd rect
			(at 0 0.799846 90)
			(size 0.4572 0.508)
			(layers "F.Cu" "F.Mask" "F.Paste")
			(net "FM_CPLD_NODE1_P1V8_STB_S_EN")
		)
		(zone
			(layer "F.Cu")
			(hatch none 0.5)
			(connect_pads
				(clearance 0)
			)
			(min_thickness 0.25)
			(keepout
				(tracks allowed)
				(vias not_allowed)
				(pads allowed)
				(copperpour not_allowed)
				(footprints allowed)
			)
			(placement
				(enabled no)
				(sheetname "")
			)
			(fill
				(thermal_gap 0.5)
				(thermal_bridge_width 0.5)
				(island_removal_mode 0)
			)
			(polygon
				(pts
					(xy 102.291388 -157.411928) (xy 102.900988 -157.411928) (xy 102.900988 -158.783528) (xy 102.291388 -158.783528)
				)
			)
		)
	)
	(footprint ""
		(layer "F.Cu")
		(at 139.98956 -114.383058 -90)
		(property "Reference" "R25"
			(at 1.995678 -3.115818 90)
			(unlocked yes)
			(layer "F.SilkS")
			(effects
				(font
					(size 0.7874 0.5842)
					(thickness 0.1524)
				)
				(justify left)
			)
		)
		(property "Value" ""
			(at 0 0 270)
			(layer "F.Fab")
			(effects
				(font
					(size 1.27 1.27)
				)
			)
		)
		(duplicate_pad_numbers_are_jumpers no)
		(fp_line
			(start -0.7874 0.4064)
			(end -0.7874 -0.4064)
			(stroke
				(width 0.1524)
				(type default)
			)
			(layer "F.SilkS")
		)
		(fp_line
			(start 0.7874 0.4064)
			(end -0.7874 0.4064)
			(stroke
				(width 0.1524)
				(type default)
			)
			(layer "F.SilkS")
		)
		(fp_line
			(start -0.7874 -0.4064)
			(end 0.7874 -0.4064)
			(stroke
				(width 0.1524)
				(type default)
			)
			(layer "F.SilkS")
		)
		(fp_line
			(start 0.7874 -0.4064)
			(end 0.7874 0.4064)
			(stroke
				(width 0.1524)
				(type default)
			)
			(layer "F.SilkS")
		)
		(fp_poly
			(pts
				(xy -0.508 0.2794) (xy -0.508 0.2286) (xy -0.635 0.2286) (xy -0.635 -0.254) (xy -0.5334 -0.254)
				(xy -0.5334 -0.2794) (xy 0.5334 -0.2794) (xy 0.5334 -0.254) (xy 0.635 -0.254) (xy 0.635 0.254) (xy 0.5334 0.254)
				(xy 0.5334 0.2794)
			)
			(stroke
				(width 0)
				(type default)
			)
			(fill no)
			(layer "F.CrtYd")
		)
		(pad "1" smd rect
			(at 0.40005 0 270)
			(size 0.4572 0.508)
			(layers "F.Cu" "F.Mask" "F.Paste")
			(net "GND")
		)
		(pad "2" smd rect
			(at -0.40005 0 270)
			(size 0.4572 0.508)
			(layers "F.Cu" "F.Mask" "F.Paste")
			(net "CLKREQC_NODE1_N")
		)
	)
	(footprint ""
		(layer "F.Cu")
		(at 152.510998 -142.88643 -90)
		(property "Reference" "R591"
			(at -1.457706 1.209802 90)
			(unlocked yes)
			(layer "F.SilkS")
			(effects
				(font
					(size 0.635 0.4064)
					(thickness 0.1524)
				)
				(justify left)
			)
		)
		(property "Value" ""
			(at 0 0 270)
			(layer "F.Fab")
			(effects
				(font
					(size 1.27 1.27)
				)
			)
		)
		(duplicate_pad_numbers_are_jumpers no)
		(fp_line
			(start -0.7874 0.4064)
			(end -0.7874 -0.4064)
			(stroke
				(width 0.1524)
				(type default)
			)
			(layer "F.SilkS")
		)
		(fp_line
			(start 0.7874 0.4064)
			(end -0.7874 0.4064)
			(stroke
				(width 0.1524)
				(type default)
			)
			(layer "F.SilkS")
		)
		(fp_line
			(start -0.7874 -0.4064)
			(end 0.7874 -0.4064)
			(stroke
				(width 0.1524)
				(type default)
			)
			(layer "F.SilkS")
		)
		(fp_line
			(start 0.7874 -0.4064)
			(end 0.7874 0.4064)
			(stroke
				(width 0.1524)
				(type default)
			)
			(layer "F.SilkS")
		)
		(fp_poly
			(pts
				(xy -0.508 0.2794) (xy -0.508 0.2286) (xy -0.635 0.2286) (xy -0.635 -0.254) (xy -0.5334 -0.254)
				(xy -0.5334 -0.2794) (xy 0.5334 -0.2794) (xy 0.5334 -0.254) (xy 0.635 -0.254) (xy 0.635 0.254) (xy 0.5334 0.254)
				(xy 0.5334 0.2794)
			)
			(stroke
				(width 0)
				(type default)
			)
			(fill no)
			(layer "F.CrtYd")
		)
		(pad "1" smd rect
			(at 0.40005 0 270)
			(size 0.4572 0.508)
			(layers "F.Cu" "F.Mask" "F.Paste")
			(net "PCH_I2C_ALERT_N")
		)
		(pad "2" smd rect
			(at -0.40005 0 270)
			(size 0.4572 0.508)
			(layers "F.Cu" "F.Mask" "F.Paste")
			(net "SMB_LAN2_ALT_N")
		)
	)
	(footprint ""
		(layer "F.Cu")
		(at 72.321166 -96.709992 -90)
		(property "Reference" "R111"
			(at 54.98719 -28.313888 90)
			(unlocked yes)
			(layer "F.SilkS")
			(effects
				(font
					(size 0.7874 0.5842)
					(thickness 0.1524)
				)
				(justify left)
			)
		)
		(property "Value" ""
			(at 0 0 270)
			(layer "F.Fab")
			(effects
				(font
					(size 1.27 1.27)
				)
			)
		)
		(duplicate_pad_numbers_are_jumpers no)
		(fp_line
			(start -0.7874 0.4064)
			(end -0.7874 -0.4064)
			(stroke
				(width 0.1524)
				(type default)
			)
			(layer "F.SilkS")
		)
		(fp_line
			(start 0.7874 0.4064)
			(end -0.7874 0.4064)
			(stroke
				(width 0.1524)
				(type default)
			)
			(layer "F.SilkS")
		)
		(fp_line
			(start -0.7874 -0.4064)
			(end 0.7874 -0.4064)
			(stroke
				(width 0.1524)
				(type default)
			)
			(layer "F.SilkS")
		)
		(fp_line
			(start 0.7874 -0.4064)
			(end 0.7874 0.4064)
			(stroke
				(width 0.1524)
				(type default)
			)
			(layer "F.SilkS")
		)
		(fp_poly
			(pts
				(xy -0.508 0.2794) (xy -0.508 0.2286) (xy -0.635 0.2286) (xy -0.635 -0.254) (xy -0.5334 -0.254)
				(xy -0.5334 -0.2794) (xy 0.5334 -0.2794) (xy 0.5334 -0.254) (xy 0.635 -0.254) (xy 0.635 0.254) (xy 0.5334 0.254)
				(xy 0.5334 0.2794)
			)
			(stroke
				(width 0)
				(type default)
			)
			(fill no)
			(layer "F.CrtYd")
		)
		(pad "1" smd rect
			(at 0.40005 0 270)
			(size 0.4572 0.508)
			(layers "F.Cu" "F.Mask" "F.Paste")
			(net "H_CPU_NODE1_ERR0_R")
		)
		(pad "2" smd rect
			(at -0.40005 0 270)
			(size 0.4572 0.508)
			(layers "F.Cu" "F.Mask" "F.Paste")
			(net "P3V3_NODE1")
		)
	)
	(footprint ""
		(layer "F.Cu")
		(at 5.48513 -167.373554 180)
		(property "Reference" "R1297"
			(at 1.65862 1.044194 0)
			(unlocked yes)
			(layer "F.SilkS")
			(effects
				(font
					(size 0.7874 0.5842)
					(thickness 0.1524)
				)
				(justify left)
			)
		)
		(property "Value" ""
			(at 0 0 180)
			(layer "F.Fab")
			(effects
				(font
					(size 1.27 1.27)
				)
			)
		)
		(duplicate_pad_numbers_are_jumpers no)
		(fp_line
			(start 0.7874 0.4064)
			(end -0.7874 0.4064)
			(stroke
				(width 0.1524)
				(type default)
			)
			(layer "F.SilkS")
		)
		(fp_line
			(start 0.7874 -0.4064)
			(end 0.7874 0.4064)
			(stroke
				(width 0.1524)
				(type default)
			)
			(layer "F.SilkS")
		)
		(fp_line
			(start -0.7874 0.4064)
			(end -0.7874 -0.4064)
			(stroke
				(width 0.1524)
				(type default)
			)
			(layer "F.SilkS")
		)
		(fp_line
			(start -0.7874 -0.4064)
			(end 0.7874 -0.4064)
			(stroke
				(width 0.1524)
				(type default)
			)
			(layer "F.SilkS")
		)
		(fp_poly
			(pts
				(xy -0.508 0.2794) (xy -0.508 0.2286) (xy -0.635 0.2286) (xy -0.635 -0.254) (xy -0.5334 -0.254)
				(xy -0.5334 -0.2794) (xy 0.5334 -0.2794) (xy 0.5334 -0.254) (xy 0.635 -0.254) (xy 0.635 0.254) (xy 0.5334 0.254)
				(xy 0.5334 0.2794)
			)
			(stroke
				(width 0)
				(type default)
			)
			(fill no)
			(layer "F.CrtYd")
		)
		(pad "1" smd rect
			(at 0.40005 0 180)
			(size 0.4572 0.508)
			(layers "F.Cu" "F.Mask" "F.Paste")
			(net "GND")
		)
		(pad "2" smd rect
			(at -0.40005 0 180)
			(size 0.4572 0.508)
			(layers "F.Cu" "F.Mask" "F.Paste")
			(net "N54258454")
		)
	)
)
